(kicad_pcb
	(version 20260206)
	(generator "pcbnew")
	(generator_version "10.0")
	(general
		(thickness 1.6)
		(legacy_teardrops no)
	)
	(paper "A4")
	(title_block
		(title "v1-pdb — T6M_PDB_D_0927_0900.brd")
		(comment 1 "Open CloudServer (Microsoft) / footprint 271 of 321 (J25), pads 157-166 of 166")
	)
	(layers
		(0 "F.Cu" signal "TOP")
		(4 "In1.Cu" signal "GND")
		(6 "In2.Cu" signal "IN1")
		(8 "In3.Cu" signal "VCC")
		(10 "In4.Cu" signal "VCC1")
		(12 "In5.Cu" signal "IN2")
		(14 "In6.Cu" signal "GND1")
		(2 "B.Cu" signal "BOTTOM")
		(9 "F.Adhes" user "F.Adhesive")
		(11 "B.Adhes" user "B.Adhesive")
		(13 "F.Paste" user "Package Geometry/Pastemask Top")
		(15 "B.Paste" user "Package Geometry/Pastemask Bottom")
		(5 "F.SilkS" user "Ref Des/Silkscreen Top")
		(7 "B.SilkS" user "Ref Des/Silkscreen Bottom")
		(1 "F.Mask" user "Board Geometry/Soldermask Top")
		(3 "B.Mask" user "Board Geometry/Soldermask Bottom")
		(17 "Dwgs.User" user "User.Drawings")
		(19 "Cmts.User" user "User.Comments")
		(21 "Eco1.User" user "User.Eco1")
		(23 "Eco2.User" user "User.Eco2")
		(25 "Edge.Cuts" user "Board Geometry/Outline")
		(27 "Margin" user)
		(31 "F.CrtYd" user "Package Geometry/Place Bound Top")
		(29 "B.CrtYd" user "Package Geometry/Place Bound Bottom")
		(35 "F.Fab" user "Ref Des/Assembly Top")
		(33 "B.Fab" user "Ref Des/Assembly Bottom")
	)
	(footprint ""
		(layer "F.Cu")
		(at 6.449822 -352.669856)
		(property "Reference" "J25"
			(at 6.653784 1.81356 90)
			(unlocked yes)
			(layer "F.SilkS")
			(effects
				(font
					(size 0.7874 0.5842)
					(thickness 0.1524)
				)
				(justify left)
			)
		)
		(property "Value" ""
			(at 0 0 0)
			(layer "F.Fab")
			(effects
				(font
					(size 1.27 1.27)
				)
			)
		)
		(duplicate_pad_numbers_are_jumpers no)
		(pad "B73" thru_hole circle
			(at -2.499868 74.000106 270)
			(size 1.016 1.016)
			(drill 0.7112)
			(layers "*.Cu" "*.Mask")
			(remove_unused_layers no)
			(net "T8_BLAD4_RXD")
			(clearance 0.1016)
			(thermal_gap 0.1016)
		)
		(pad "B74" thru_hole circle
			(at -4.499864 75.000104 270)
			(size 1.016 1.016)
			(drill 0.7112)
			(layers "*.Cu" "*.Mask")
			(remove_unused_layers no)
			(net "T8_BLAD4_TXD")
			(clearance 0.1016)
			(thermal_gap 0.1016)
		)
		(pad "B75" thru_hole circle
			(at -2.499868 76.000102 270)
			(size 1.016 1.016)
			(drill 0.7112)
			(layers "*.Cu" "*.Mask")
			(remove_unused_layers no)
			(net "GND")
			(clearance 0.1016)
			(thermal_gap 0.1016)
		)
		(pad "B76" thru_hole circle
			(at -4.499864 77.0001 270)
			(size 1.016 1.016)
			(drill 0.7112)
			(layers "*.Cu" "*.Mask")
			(remove_unused_layers no)
			(net "T6_BLAD1_EN")
			(clearance 0.1016)
			(thermal_gap 0.1016)
		)
		(pad "B77" thru_hole circle
			(at -2.499868 78.000098 270)
			(size 1.016 1.016)
			(drill 0.7112)
			(layers "*.Cu" "*.Mask")
			(remove_unused_layers no)
			(net "T6_BLAD2_EN")
			(clearance 0.1016)
			(thermal_gap 0.1016)
		)
		(pad "B78" thru_hole circle
			(at -4.499864 79.000096 270)
			(size 1.016 1.016)
			(drill 0.7112)
			(layers "*.Cu" "*.Mask")
			(remove_unused_layers no)
			(net "T6_BLAD3_EN")
			(clearance 0.1016)
			(thermal_gap 0.1016)
		)
		(pad "B79" thru_hole circle
			(at -2.499868 80.000094 270)
			(size 1.016 1.016)
			(drill 0.7112)
			(layers "*.Cu" "*.Mask")
			(remove_unused_layers no)
			(net "T6_BLAD4_EN")
			(clearance 0.1016)
			(thermal_gap 0.1016)
		)
		(pad "B80" thru_hole circle
			(at -4.499864 81.000092 270)
			(size 1.016 1.016)
			(drill 0.7112)
			(layers "*.Cu" "*.Mask")
			(remove_unused_layers no)
			(net "GND")
			(clearance 0.1016)
			(thermal_gap 0.1016)
		)
		(pad "B81" thru_hole circle
			(at -2.499868 82.00009 270)
			(size 1.016 1.016)
			(drill 0.7112)
			(layers "*.Cu" "*.Mask")
			(remove_unused_layers no)
			(net "T6_BLAD1_RXD")
			(clearance 0.1016)
			(thermal_gap 0.1016)
		)
		(pad "B82" thru_hole circle
			(at -4.499864 83.000088 270)
			(size 1.016 1.016)
			(drill 0.7112)
			(layers "*.Cu" "*.Mask")
			(remove_unused_layers no)
			(net "T6_BLAD1_TXD")
			(clearance 0.1016)
			(thermal_gap 0.1016)
		)
	)
)
